# T6G (Grand Teton) — schematic netlist excerpt (pin names and nets, part order shuffled) for the footprints in the layout excerpt that follows; sources: Cadence DE-HDL packaged netlist, KiCad conversion of 04192023_DAF0TMB3IC0_F0TG_MB_C_brd_V02_OCP.brd

R4450  Q_RES  0 5% CHIP  pkg 0402LF  page 176 : A = USB_CPU0_HUB1_VBUS_DS ; B = P5V_AUX

(kicad_pcb
	(version 20260206)
	(generator "pcbnew")
	(generator_version "10.0")
	(general
		(thickness 1.6)
		(legacy_teardrops no)
	)
	(paper "A4")
	(title_block
		(title "04192023_DAF0TMB3IC0_F0TG_MB_C_brd_V02_OCP.brd")
		(comment 1 "Grand Teton / footprints 1264-1264 of 8354")
	)
	(layers
		(0 "F.Cu" signal "TOP")
		(4 "In1.Cu" signal "GND")
		(6 "In2.Cu" signal "IN1")
		(8 "In3.Cu" signal "GND1")
		(10 "In4.Cu" signal "IN2")
		(12 "In5.Cu" signal "GND2")
		(14 "In6.Cu" signal "IN3")
		(16 "In7.Cu" signal "GND3")
		(18 "In8.Cu" signal "VCC")
		(20 "In9.Cu" signal "VCC1")
		(22 "In10.Cu" signal "GND4")
		(24 "In11.Cu" signal "IN4")
		(26 "In12.Cu" signal "GND5")
		(28 "In13.Cu" signal "IN5")
		(30 "In14.Cu" signal "GND6")
		(32 "In15.Cu" signal "IN6")
		(34 "In16.Cu" signal "GND7")
		(2 "B.Cu" signal "BOTTOM")
		(9 "F.Adhes" user "F.Adhesive")
		(11 "B.Adhes" user "B.Adhesive")
		(13 "F.Paste" user "Package Geometry/Pastemask Top")
		(15 "B.Paste" user "Package Geometry/Pastemask Bottom")
		(5 "F.SilkS" user "Ref Des/Silkscreen Top")
		(7 "B.SilkS" user "Ref Des/Silkscreen Bottom")
		(1 "F.Mask" user "Board Geometry/Soldermask Top")
		(3 "B.Mask" user "Board Geometry/Soldermask Bottom")
		(17 "Dwgs.User" user "User.Drawings")
		(19 "Cmts.User" user "User.Comments")
		(21 "Eco1.User" user "User.Eco1")
		(23 "Eco2.User" user "User.Eco2")
		(25 "Edge.Cuts" user "Board Geometry/Outline")
		(27 "Margin" user)
		(31 "F.CrtYd" user "Package Geometry/Place Bound Top")
		(29 "B.CrtYd" user "Package Geometry/Place Bound Bottom")
		(35 "F.Fab" user "Ref Des/Assembly Top")
		(33 "B.Fab" user "Ref Des/Assembly Bottom")
	)
	(footprint ""
		(layer "F.Cu")
		(at 140.765784 -47.309024 90)
		(property "Reference" "R4450"
			(at 0 0 90)
			(layer "F.SilkS")
			(hide yes)
			(effects
				(font
					(size 1.27 1.27)
				)
			)
		)
		(property "Value" ""
			(at 0 0 90)
			(layer "F.Fab")
			(effects
				(font
					(size 1.27 1.27)
				)
			)
		)
		(duplicate_pad_numbers_are_jumpers no)
		(fp_line
			(start 0.7874 -0.4064)
			(end 0.7874 0.4064)
			(stroke
				(width 0.1524)
				(type default)
			)
			(layer "F.SilkS")
		)
		(fp_line
			(start -0.7874 -0.4064)
			(end 0.7874 -0.4064)
			(stroke
				(width 0.1524)
				(type default)
			)
			(layer "F.SilkS")
		)
		(fp_line
			(start 0.7874 0.4064)
			(end -0.7874 0.4064)
			(stroke
				(width 0.1524)
				(type default)
			)
			(layer "F.SilkS")
		)
		(fp_line
			(start -0.7874 0.4064)
			(end -0.7874 -0.4064)
			(stroke
				(width 0.1524)
				(type default)
			)
			(layer "F.SilkS")
		)
		(fp_line
			(start -0.12065 -0.305054)
			(end -0.12065 -0.2794)
			(stroke
				(width 0.1)
				(type default)
			)
			(layer "F.Fab")
		)
		(fp_line
			(start -0.67945 -0.305054)
			(end -0.12065 -0.305054)
			(stroke
				(width 0.1)
				(type default)
			)
			(layer "F.Fab")
		)
		(fp_line
			(start 0.67945 -0.3048)
			(end 0.67945 0.3048)
			(stroke
				(width 0.1)
				(type default)
			)
			(layer "F.Fab")
		)
		(fp_line
			(start 0.12065 -0.3048)
			(end 0.67945 -0.3048)
			(stroke
				(width 0.1)
				(type default)
			)
			(layer "F.Fab")
		)
		(fp_line
			(start 0.12065 -0.2794)
			(end 0.12065 -0.3048)
			(stroke
				(width 0.1)
				(type default)
			)
			(layer "F.Fab")
		)
		(fp_line
			(start -0.12065 -0.2794)
			(end 0.12065 -0.2794)
			(stroke
				(width 0.1)
				(type default)
			)
			(layer "F.Fab")
		)
		(fp_line
			(start 0.120396 0.2794)
			(end -0.12065 0.2794)
			(stroke
				(width 0.1)
				(type default)
			)
			(layer "F.Fab")
		)
		(fp_line
			(start -0.12065 0.2794)
			(end -0.12065 0.3048)
			(stroke
				(width 0.1)
				(type default)
			)
			(layer "F.Fab")
		)
		(fp_line
			(start 0.67945 0.3048)
			(end 0.120396 0.3048)
			(stroke
				(width 0.1)
				(type default)
			)
			(layer "F.Fab")
		)
		(fp_line
			(start 0.120396 0.3048)
			(end 0.120396 0.2794)
			(stroke
				(width 0.1)
				(type default)
			)
			(layer "F.Fab")
		)
		(fp_line
			(start -0.12065 0.3048)
			(end -0.67945 0.3048)
			(stroke
				(width 0.1)
				(type default)
			)
			(layer "F.Fab")
		)
		(fp_line
			(start -0.67945 0.3048)
			(end -0.67945 -0.305054)
			(stroke
				(width 0.1)
				(type default)
			)
			(layer "F.Fab")
		)
		(pad "1" smd circle
			(at -0.40005 0 90)
			(size 0 0)
			(layers "F.Cu" "F.Mask" "F.Paste")
			(net "USB_CPU0_HUB1_VBUS_DS")
		)
		(pad "2" smd circle
			(at 0.40005 0 90)
			(size 0 0)
			(layers "F.Cu" "F.Mask" "F.Paste")
			(net "P5V_AUX")
		)
	)
)
